(kicad_pcb
	(version 20260206)
	(generator "pcbnew")
	(generator_version "10.0")
	(general
		(thickness 1.6)
		(legacy_teardrops no)
	)
	(paper "A4")
	(title_block
		(title "panther-plus-userver — 13130-1b_20150205.brd")
		(comment 1 "Honey Badger (Wiwynn) / footprints 9-16 of 1509")
	)
	(layers
		(0 "F.Cu" signal "TOP")
		(4 "In1.Cu" signal "L2")
		(6 "In2.Cu" signal "L3")
		(8 "In3.Cu" signal "L4")
		(10 "In4.Cu" signal "L5")
		(12 "In5.Cu" signal "L6")
		(14 "In6.Cu" signal "L7")
		(16 "In7.Cu" signal "L8")
		(18 "In8.Cu" signal "L9")
		(20 "In9.Cu" signal "L10")
		(22 "In10.Cu" signal "L11")
		(2 "B.Cu" signal "BOTTOM")
		(9 "F.Adhes" user "F.Adhesive")
		(11 "B.Adhes" user "B.Adhesive")
		(13 "F.Paste" user "Package Geometry/Pastemask Top")
		(15 "B.Paste" user "Package Geometry/Pastemask Bottom")
		(5 "F.SilkS" user "Ref Des/Silkscreen Top")
		(7 "B.SilkS" user "Ref Des/Silkscreen Bottom")
		(1 "F.Mask" user "Board Geometry/Soldermask Top")
		(3 "B.Mask" user "Board Geometry/Soldermask Bottom")
		(17 "Dwgs.User" user "User.Drawings")
		(19 "Cmts.User" user "User.Comments")
		(21 "Eco1.User" user "User.Eco1")
		(23 "Eco2.User" user "User.Eco2")
		(25 "Edge.Cuts" user "Board Geometry/Outline")
		(27 "Margin" user)
		(31 "F.CrtYd" user "Package Geometry/Place Bound Top")
		(29 "B.CrtYd" user "Package Geometry/Place Bound Bottom")
		(35 "F.Fab" user "Ref Des/Assembly Top")
		(33 "B.Fab" user "Ref Des/Assembly Bottom")
	)
	(footprint ""
		(layer "F.Cu")
		(at 51.435 -23.495 90)
		(property "Reference" "R448"
			(at 0 0 90)
			(layer "F.SilkS")
			(hide yes)
			(effects
				(font
					(size 1.27 1.27)
				)
			)
		)
		(property "Value" "4K7R2F-GP"
			(at 1.7907 -1.1176 90)
			(unlocked yes)
			(layer "F.Fab")
			(hide yes)
			(effects
				(font
					(size 1.016 1.016)
					(thickness 0.1524)
				)
			)
		)
		(property "Device Type" "R402H16"
			(at 1.7907 -2.6416 90)
			(unlocked yes)
			(layer "F.Fab")
			(hide yes)
			(effects
				(font
					(size 1.016 1.016)
					(thickness 0.1524)
				)
			)
		)
		(duplicate_pad_numbers_are_jumpers no)
		(fp_rect
			(start -0.381 0.8382)
			(end 0.381 -0.8382)
			(stroke
				(width 0)
				(type default)
			)
			(fill no)
			(layer "F.CrtYd")
		)
		(fp_rect
			(start -0.381 0.8382)
			(end 0.381 -0.8382)
			(stroke
				(width 0)
				(type default)
			)
			(fill no)
			(layer "F.Fab")
		)
		(pad "1" smd custom
			(at 0 -0.4318 90)
			(size 0.127 0.127)
			(layers "F.Cu" "F.Mask" "F.Paste")
			(net "CLKBUFF_OE7#")
			(options
				(clearance outline)
				(anchor circle)
			)
			(primitives
				(gr_poly
					(pts
						(arc
							(start -0.2032 -0.2794)
							(mid -0.239121 -0.264521)
							(end -0.254 -0.2286)
						)
						(arc
							(start -0.254 0.2286)
							(mid -0.239121 0.264521)
							(end -0.2032 0.2794)
						)
						(arc
							(start 0.2032 0.2794)
							(mid 0.239121 0.264521)
							(end 0.254 0.2286)
						)
						(arc
							(start 0.254 -0.2286)
							(mid 0.239121 -0.264521)
							(end 0.2032 -0.2794)
						)
					)
					(width 0)
					(fill yes)
				)
			)
		)
		(pad "2" smd custom
			(at 0 0.4318 90)
			(size 0.127 0.127)
			(layers "F.Cu" "F.Mask" "F.Paste")
			(net "GND")
			(options
				(clearance outline)
				(anchor circle)
			)
			(primitives
				(gr_poly
					(pts
						(arc
							(start -0.2032 -0.2794)
							(mid -0.239121 -0.264521)
							(end -0.254 -0.2286)
						)
						(arc
							(start -0.254 0.2286)
							(mid -0.239121 0.264521)
							(end -0.2032 0.2794)
						)
						(arc
							(start 0.2032 0.2794)
							(mid 0.239121 0.264521)
							(end 0.254 0.2286)
						)
						(arc
							(start 0.254 -0.2286)
							(mid 0.239121 -0.264521)
							(end 0.2032 -0.2794)
						)
					)
					(width 0)
					(fill yes)
				)
			)
		)
	)
	(footprint ""
		(layer "F.Cu")
		(at 138.4046 -51.9684 90)
		(property "Reference" "R118"
			(at 0 0 90)
			(layer "F.SilkS")
			(hide yes)
			(effects
				(font
					(size 1.27 1.27)
				)
			)
		)
		(property "Value" "0R2J-2-GP"
			(at 1.7907 -1.1176 90)
			(unlocked yes)
			(layer "F.Fab")
			(hide yes)
			(effects
				(font
					(size 1.016 1.016)
					(thickness 0.1524)
				)
			)
		)
		(property "Device Type" "R402H16"
			(at 1.7907 -2.6416 90)
			(unlocked yes)
			(layer "F.Fab")
			(hide yes)
			(effects
				(font
					(size 1.016 1.016)
					(thickness 0.1524)
				)
			)
		)
		(duplicate_pad_numbers_are_jumpers no)
		(fp_rect
			(start -0.381 0.8382)
			(end 0.381 -0.8382)
			(stroke
				(width 0)
				(type default)
			)
			(fill no)
			(layer "F.CrtYd")
		)
		(fp_rect
			(start -0.381 0.8382)
			(end 0.381 -0.8382)
			(stroke
				(width 0)
				(type default)
			)
			(fill no)
			(layer "F.Fab")
		)
		(pad "1" smd custom
			(at 0 -0.4318 90)
			(size 0.127 0.127)
			(layers "F.Cu" "F.Mask" "F.Paste")
			(net "C_NCONFIG#")
			(options
				(clearance outline)
				(anchor circle)
			)
			(primitives
				(gr_poly
					(pts
						(arc
							(start -0.2032 -0.2794)
							(mid -0.239121 -0.264521)
							(end -0.254 -0.2286)
						)
						(arc
							(start -0.254 0.2286)
							(mid -0.239121 0.264521)
							(end -0.2032 0.2794)
						)
						(arc
							(start 0.2032 0.2794)
							(mid 0.239121 0.264521)
							(end 0.254 0.2286)
						)
						(arc
							(start 0.254 -0.2286)
							(mid 0.239121 -0.264521)
							(end 0.2032 -0.2794)
						)
					)
					(width 0)
					(fill yes)
				)
			)
		)
		(pad "2" smd custom
			(at 0 0.4318 90)
			(size 0.127 0.127)
			(layers "F.Cu" "F.Mask" "F.Paste")
			(net "SPI_SW_NCONFIG#")
			(options
				(clearance outline)
				(anchor circle)
			)
			(primitives
				(gr_poly
					(pts
						(arc
							(start -0.2032 -0.2794)
							(mid -0.239121 -0.264521)
							(end -0.254 -0.2286)
						)
						(arc
							(start -0.254 0.2286)
							(mid -0.239121 0.264521)
							(end -0.2032 0.2794)
						)
						(arc
							(start 0.2032 0.2794)
							(mid 0.239121 0.264521)
							(end 0.254 0.2286)
						)
						(arc
							(start 0.254 -0.2286)
							(mid 0.239121 -0.264521)
							(end 0.2032 -0.2794)
						)
					)
					(width 0)
					(fill yes)
				)
			)
		)
	)
	(footprint ""
		(layer "F.Cu")
		(at 170.688 -26.543 -90)
		(property "Reference" "PU9"
			(at 0 0 270)
			(layer "F.SilkS")
			(hide yes)
			(effects
				(font
					(size 1.27 1.27)
				)
			)
		)
		(property "Value" "LD1117AG-12-AA3-A-R-GP"
			(at -0.0508 -10.3632 270)
			(unlocked yes)
			(layer "F.Fab")
			(hide yes)
			(effects
				(font
					(size 1.016 1.016)
					(thickness 0.1524)
				)
			)
		)
		(property "Device Type" "SOT-223H71"
			(at -0.1524 -12.3952 270)
			(unlocked yes)
			(layer "F.Fab")
			(hide yes)
			(effects
				(font
					(size 1.016 1.016)
					(thickness 0.1524)
				)
			)
		)
		(duplicate_pad_numbers_are_jumpers no)
		(fp_poly
			(pts
				(xy -2.3749 1.0922) (xy -1.9431 1.524) (xy -2.8067 1.524)
			)
			(stroke
				(width 0)
				(type default)
			)
			(fill yes)
			(layer "F.SilkS")
		)
		(fp_poly
			(pts
				(xy 3.048 1.0795) (xy 3.048 -0.8001) (xy 3.5052 -0.8001) (xy 3.5052 -4.8133) (xy 1.8796 -4.8133)
				(xy 1.8796 -6.6675) (xy -1.8796 -6.6675) (xy -1.8796 -4.8133) (xy -3.5052 -4.8133) (xy -3.5052 -0.8001)
				(xy -3.048 -0.8001) (xy -3.048 1.0795)
			)
			(stroke
				(width 0)
				(type default)
			)
			(fill no)
			(layer "F.CrtYd")
		)
		(fp_poly
			(pts
				(xy 3.048 1.0795) (xy 3.048 -0.5207) (xy 3.048 -0.6731) (xy 3.048 -0.8001) (xy 3.5052 -0.8001) (xy 3.5052 -4.6863)
				(xy 3.5052 -4.8133) (xy 1.905 -4.8133) (xy 1.8796 -4.8133) (xy 1.8796 -6.6675) (xy -1.8796 -6.6675)
				(xy -1.8796 -4.8133) (xy -1.905 -4.8133) (xy -3.5052 -4.8133) (xy -3.5052 -4.6863) (xy -3.5052 -0.8001)
				(xy -3.048 -0.8001) (xy -3.048 -0.6731) (xy -3.048 1.0795)
			)
			(stroke
				(width 0)
				(type default)
			)
			(fill no)
			(layer "F.Fab")
		)
		(pad "1" smd rect
			(at -2.286 0 270)
			(size 1.27 1.905)
			(layers "F.Cu" "F.Mask" "F.Paste")
			(net "GND")
		)
		(pad "2" smd custom
			(at 0 0 270)
			(size 0.8763 0.8763)
			(layers "F.Cu" "F.Mask" "F.Paste")
			(net "P1V2_STBY_LDO_OUT2")
			(options
				(clearance outline)
				(anchor circle)
			)
			(primitives
				(gr_poly
					(pts
						(xy 1.7526 -1.8415) (xy 0.381 -1.8415) (xy 0.381 1.8415) (xy 0.635 1.8415) (xy 0.635 3.7465) (xy -0.635 3.7465)
						(xy -0.635 1.8415) (xy -0.381 1.8415) (xy -0.381 -1.8415) (xy -1.7526 -1.8415) (xy -1.7526 -3.7465)
						(xy 1.7526 -3.7465)
					)
					(width 0)
					(fill yes)
				)
			)
		)
		(pad "3" smd rect
			(at 2.286 0 270)
			(size 1.27 1.905)
			(layers "F.Cu" "F.Mask" "F.Paste")
			(net "P1V8_STBY_LDO_IN2")
		)
	)
	(footprint ""
		(layer "F.Cu")
		(at 181.737 -14.859 180)
		(property "Reference" "PC117"
			(at 0 0 180)
			(layer "F.SilkS")
			(hide yes)
			(effects
				(font
					(size 1.27 1.27)
				)
			)
		)
		(property "Value" "SC10U6D3V3MX-GP"
			(at 0 -2.8194 180)
			(unlocked yes)
			(layer "F.Fab")
			(hide yes)
			(effects
				(font
					(size 1.016 1.016)
					(thickness 0.1524)
				)
			)
		)
		(property "Device Type" "C603H38"
			(at 0 -4.3434 180)
			(unlocked yes)
			(layer "F.Fab")
			(hide yes)
			(effects
				(font
					(size 1.016 1.016)
					(thickness 0.1524)
				)
			)
		)
		(duplicate_pad_numbers_are_jumpers no)
		(fp_line
			(start -0.4064 0)
			(end 0.4064 0)
			(stroke
				(width 0.2286)
				(type default)
			)
			(layer "F.SilkS")
		)
		(fp_rect
			(start -0.635 1.1811)
			(end 0.635 -1.1811)
			(stroke
				(width 0)
				(type default)
			)
			(fill no)
			(layer "F.CrtYd")
		)
		(fp_rect
			(start -0.635 1.1811)
			(end 0.635 -1.1811)
			(stroke
				(width 0)
				(type default)
			)
			(fill no)
			(layer "F.Fab")
		)
		(pad "1" smd custom
			(at 0 -0.6604 180)
			(size 0.19685 0.19685)
			(layers "F.Cu" "F.Mask" "F.Paste")
			(net "GND")
			(options
				(clearance outline)
				(anchor circle)
			)
			(primitives
				(gr_poly
					(pts
						(arc
							(start 0.508 -0.2921)
							(mid 0.478242 -0.363942)
							(end 0.4064 -0.3937)
						)
						(arc
							(start -0.4064 -0.3937)
							(mid -0.478242 -0.363942)
							(end -0.508 -0.2921)
						)
						(arc
							(start -0.508 0.2921)
							(mid -0.478242 0.363942)
							(end -0.4064 0.3937)
						)
						(arc
							(start 0.4064 0.3937)
							(mid 0.478242 0.363942)
							(end 0.508 0.2921)
						)
					)
					(width 0)
					(fill yes)
				)
			)
		)
		(pad "2" smd custom
			(at 0 0.6604 180)
			(size 0.19685 0.19685)
			(layers "F.Cu" "F.Mask" "F.Paste")
			(net "PV_VDDR")
			(options
				(clearance outline)
				(anchor circle)
			)
			(primitives
				(gr_poly
					(pts
						(arc
							(start 0.508 -0.2921)
							(mid 0.478242 -0.363942)
							(end 0.4064 -0.3937)
						)
						(arc
							(start -0.4064 -0.3937)
							(mid -0.478242 -0.363942)
							(end -0.508 -0.2921)
						)
						(arc
							(start -0.508 0.2921)
							(mid -0.478242 0.363942)
							(end -0.4064 0.3937)
						)
						(arc
							(start 0.4064 0.3937)
							(mid 0.478242 0.363942)
							(end 0.508 0.2921)
						)
					)
					(width 0)
					(fill yes)
				)
			)
		)
	)
	(footprint ""
		(layer "F.Cu")
		(at 193.04 -30.988 90)
		(property "Reference" "PR143"
			(at 0 0 90)
			(layer "F.SilkS")
			(hide yes)
			(effects
				(font
					(size 1.27 1.27)
				)
			)
		)
		(property "Value" "0R2J-2-GP"
			(at 1.7907 -1.1176 90)
			(unlocked yes)
			(layer "F.Fab")
			(hide yes)
			(effects
				(font
					(size 1.016 1.016)
					(thickness 0.1524)
				)
			)
		)
		(property "Device Type" "R402H16"
			(at 1.7907 -2.6416 90)
			(unlocked yes)
			(layer "F.Fab")
			(hide yes)
			(effects
				(font
					(size 1.016 1.016)
					(thickness 0.1524)
				)
			)
		)
		(duplicate_pad_numbers_are_jumpers no)
		(fp_rect
			(start -0.381 0.8382)
			(end 0.381 -0.8382)
			(stroke
				(width 0)
				(type default)
			)
			(fill no)
			(layer "F.CrtYd")
		)
		(fp_rect
			(start -0.381 0.8382)
			(end 0.381 -0.8382)
			(stroke
				(width 0)
				(type default)
			)
			(fill no)
			(layer "F.Fab")
		)
		(pad "1" smd custom
			(at 0 -0.4318 90)
			(size 0.127 0.127)
			(layers "F.Cu" "F.Mask" "F.Paste")
			(net "VR_PVDDR_A_VIN")
			(options
				(clearance outline)
				(anchor circle)
			)
			(primitives
				(gr_poly
					(pts
						(arc
							(start -0.2032 -0.2794)
							(mid -0.239121 -0.264521)
							(end -0.254 -0.2286)
						)
						(arc
							(start -0.254 0.2286)
							(mid -0.239121 0.264521)
							(end -0.2032 0.2794)
						)
						(arc
							(start 0.2032 0.2794)
							(mid 0.239121 0.264521)
							(end 0.254 0.2286)
						)
						(arc
							(start 0.254 -0.2286)
							(mid 0.239121 -0.264521)
							(end 0.2032 -0.2794)
						)
					)
					(width 0)
					(fill yes)
				)
			)
		)
		(pad "2" smd custom
			(at 0 0.4318 90)
			(size 0.127 0.127)
			(layers "F.Cu" "F.Mask" "F.Paste")
			(net "P12V")
			(options
				(clearance outline)
				(anchor circle)
			)
			(primitives
				(gr_poly
					(pts
						(arc
							(start -0.2032 -0.2794)
							(mid -0.239121 -0.264521)
							(end -0.254 -0.2286)
						)
						(arc
							(start -0.254 0.2286)
							(mid -0.239121 0.264521)
							(end -0.2032 0.2794)
						)
						(arc
							(start 0.2032 0.2794)
							(mid 0.239121 0.264521)
							(end 0.254 0.2286)
						)
						(arc
							(start 0.254 -0.2286)
							(mid 0.239121 -0.264521)
							(end 0.2032 -0.2794)
						)
					)
					(width 0)
					(fill yes)
				)
			)
		)
	)
	(footprint ""
		(layer "F.Cu")
		(at 39.64178 -40.31488 90)
		(property "Reference" "TP20"
			(at 0 0 90)
			(layer "F.SilkS")
			(hide yes)
			(effects
				(font
					(size 1.27 1.27)
				)
			)
		)
		(property "Value" "TPAD28-1-GP-U"
			(at 0.0508 -1.9304 90)
			(unlocked yes)
			(layer "F.Fab")
			(hide yes)
			(effects
				(font
					(size 1.016 1.016)
					(thickness 0.1524)
				)
			)
		)
		(property "Device Type" "TPAD28-1-U"
			(at 0.0508 -3.4544 90)
			(unlocked yes)
			(layer "F.Fab")
			(hide yes)
			(effects
				(font
					(size 1.016 1.016)
					(thickness 0.1524)
				)
			)
		)
		(duplicate_pad_numbers_are_jumpers no)
		(fp_poly
			(pts
				(arc
					(start 0 0.3556)
					(mid 0 -0.3556)
					(end 0 0.3556)
				)
			)
			(stroke
				(width 0)
				(type default)
			)
			(fill no)
			(layer "F.CrtYd")
		)
		(fp_poly
			(pts
				(arc
					(start 0 0.9525)
					(mid 0 -0.9525)
					(end 0 0.9525)
				)
			)
			(stroke
				(width 0)
				(type default)
			)
			(fill no)
			(layer "F.Fab")
		)
		(pad "1" smd circle
			(at 0 0 90)
			(size 0.7112 0.7112)
			(layers "F.Cu" "F.Mask" "F.Paste")
			(net "TP_XDP0_TCK1")
		)
	)
	(footprint ""
		(layer "F.Cu")
		(at 160.02 -59.309)
		(property "Reference" "C374"
			(at 0 0 0)
			(layer "F.SilkS")
			(hide yes)
			(effects
				(font
					(size 1.27 1.27)
				)
			)
		)
		(property "Value" "SC47U6D3V5MX-1-GP"
			(at 0 -4.9022 0)
			(unlocked yes)
			(layer "F.Fab")
			(hide yes)
			(effects
				(font
					(size 1.016 1.016)
					(thickness 0.1524)
				)
			)
		)
		(property "Device Type" "C805H54"
			(at 0 -6.8072 0)
			(unlocked yes)
			(layer "F.Fab")
			(hide yes)
			(effects
				(font
					(size 1.016 1.016)
					(thickness 0.1524)
				)
			)
		)
		(duplicate_pad_numbers_are_jumpers no)
		(fp_line
			(start 0.6096 0)
			(end -0.6096 0)
			(stroke
				(width 0.3048)
				(type default)
			)
			(layer "F.SilkS")
		)
		(fp_poly
			(pts
				(xy -0.9017 1.4351) (xy 0.9017 1.4351) (xy 0.9017 -1.4351) (xy -0.9017 -1.4351)
			)
			(stroke
				(width 0)
				(type default)
			)
			(fill no)
			(layer "F.CrtYd")
		)
		(fp_poly
			(pts
				(xy 0.9017 1.4351) (xy 0.9017 -1.4351) (xy -0.9017 -1.4351) (xy -0.9017 1.4351)
			)
			(stroke
				(width 0)
				(type default)
			)
			(fill no)
			(layer "F.Fab")
		)
		(pad "1" smd rect
			(at 0 -0.8382)
			(size 1.5494 0.9398)
			(layers "F.Cu" "F.Mask" "F.Paste")
			(net "PV_VDDR")
		)
		(pad "2" smd rect
			(at 0 0.8382)
			(size 1.5494 0.9398)
			(layers "F.Cu" "F.Mask" "F.Paste")
			(net "GND")
		)
	)
	(footprint ""
		(layer "F.Cu")
		(at 46.228 -33.274 -90)
		(property "Reference" "R241"
			(at 0 0 270)
			(layer "F.SilkS")
			(hide yes)
			(effects
				(font
					(size 1.27 1.27)
				)
			)
		)
		(property "Value" "1KR2F-3-GP"
			(at 0.064008 -3.993896 270)
			(unlocked yes)
			(layer "F.Fab")
			(hide yes)
			(effects
				(font
					(size 1.016 1.016)
					(thickness 0.1524)
				)
			)
		)
		(property "Device Type" "R402H16"
			(at 0.064008 -5.517896 270)
			(unlocked yes)
			(layer "F.Fab")
			(hide yes)
			(effects
				(font
					(size 1.016 1.016)
					(thickness 0.1524)
				)
			)
		)
		(duplicate_pad_numbers_are_jumpers no)
		(fp_rect
			(start -0.381 0.8382)
			(end 0.381 -0.8382)
			(stroke
				(width 0)
				(type default)
			)
			(fill no)
			(layer "F.CrtYd")
		)
		(fp_rect
			(start -0.381 0.8382)
			(end 0.381 -0.8382)
			(stroke
				(width 0)
				(type default)
			)
			(fill no)
			(layer "F.Fab")
		)
		(pad "1" smd custom
			(at 0 -0.4318 270)
			(size 0.127 0.127)
			(layers "F.Cu" "F.Mask" "F.Paste")
			(net "P3V3_CPU")
			(options
				(clearance outline)
				(anchor circle)
			)
			(primitives
				(gr_poly
					(pts
						(arc
							(start -0.2032 -0.2794)
							(mid -0.239121 -0.264521)
							(end -0.254 -0.2286)
						)
						(arc
							(start -0.254 0.2286)
							(mid -0.239121 0.264521)
							(end -0.2032 0.2794)
						)
						(arc
							(start 0.2032 0.2794)
							(mid 0.239121 0.264521)
							(end 0.254 0.2286)
						)
						(arc
							(start 0.254 -0.2286)
							(mid 0.239121 -0.264521)
							(end 0.2032 -0.2794)
						)
					)
					(width 0)
					(fill yes)
				)
			)
		)
		(pad "2" smd custom
			(at 0 0.4318 270)
			(size 0.127 0.127)
			(layers "F.Cu" "F.Mask" "F.Paste")
			(net "XDP_PWRBTN#")
			(options
				(clearance outline)
				(anchor circle)
			)
			(primitives
				(gr_poly
					(pts
						(arc
							(start -0.2032 -0.2794)
							(mid -0.239121 -0.264521)
							(end -0.254 -0.2286)
						)
						(arc
							(start -0.254 0.2286)
							(mid -0.239121 0.264521)
							(end -0.2032 0.2794)
						)
						(arc
							(start 0.2032 0.2794)
							(mid 0.239121 0.264521)
							(end 0.254 0.2286)
						)
						(arc
							(start 0.254 -0.2286)
							(mid 0.239121 -0.264521)
							(end 0.2032 -0.2794)
						)
					)
					(width 0)
					(fill yes)
				)
			)
		)
	)
)
